# T6G (Grand Teton) — schematic netlist excerpt (pin names and nets, part order shuffled) for the footprints in the layout excerpt that follows; sources: Cadence DE-HDL packaged netlist, KiCad conversion of 04192023_DAF0TMB3IC0_F0TG_MB_C_brd_V02_OCP.brd

C892  Q_CAP_DIFFBUS  DIFF BUS_0.22UF 6.3V 20% X6S  pkg C0201  page 64 : \1\ = P5E_CPU0_P3_TX_C_DN<4> ; \2\ = P5E_CPU0_P3_TX_DN<4>
R3608  Q_RES  4.7K 1% CHIP  pkg 0402LF  page 237 : A = GND ; B = INA230_3_A1
R1364  Q_RES  1K 1% CHIP  pkg 0201LF  page 276 : A = JTAG_TRST_RT_CPU0_P0_N ; B = GND
R1041  Q_RES  200 1% CHIP  pkg 0201LF  page 288 : A = RT_CPU0_P1_VQPS ; B = GND

(kicad_pcb
	(version 20260206)
	(generator "pcbnew")
	(generator_version "10.0")
	(general
		(thickness 1.6)
		(legacy_teardrops no)
	)
	(paper "A4")
	(title_block
		(title "04192023_DAF0TMB3IC0_F0TG_MB_C_brd_V02_OCP.brd")
		(comment 1 "Grand Teton / footprints 240-243 of 8354")
	)
	(layers
		(0 "F.Cu" signal "TOP")
		(4 "In1.Cu" signal "GND")
		(6 "In2.Cu" signal "IN1")
		(8 "In3.Cu" signal "GND1")
		(10 "In4.Cu" signal "IN2")
		(12 "In5.Cu" signal "GND2")
		(14 "In6.Cu" signal "IN3")
		(16 "In7.Cu" signal "GND3")
		(18 "In8.Cu" signal "VCC")
		(20 "In9.Cu" signal "VCC1")
		(22 "In10.Cu" signal "GND4")
		(24 "In11.Cu" signal "IN4")
		(26 "In12.Cu" signal "GND5")
		(28 "In13.Cu" signal "IN5")
		(30 "In14.Cu" signal "GND6")
		(32 "In15.Cu" signal "IN6")
		(34 "In16.Cu" signal "GND7")
		(2 "B.Cu" signal "BOTTOM")
		(9 "F.Adhes" user "F.Adhesive")
		(11 "B.Adhes" user "B.Adhesive")
		(13 "F.Paste" user "Package Geometry/Pastemask Top")
		(15 "B.Paste" user "Package Geometry/Pastemask Bottom")
		(5 "F.SilkS" user "Ref Des/Silkscreen Top")
		(7 "B.SilkS" user "Ref Des/Silkscreen Bottom")
		(1 "F.Mask" user "Board Geometry/Soldermask Top")
		(3 "B.Mask" user "Board Geometry/Soldermask Bottom")
		(17 "Dwgs.User" user "User.Drawings")
		(19 "Cmts.User" user "User.Comments")
		(21 "Eco1.User" user "User.Eco1")
		(23 "Eco2.User" user "User.Eco2")
		(25 "Edge.Cuts" user "Board Geometry/Outline")
		(27 "Margin" user)
		(31 "F.CrtYd" user "Package Geometry/Place Bound Top")
		(29 "B.CrtYd" user "Package Geometry/Place Bound Bottom")
		(35 "F.Fab" user "Ref Des/Assembly Top")
		(33 "B.Fab" user "Ref Des/Assembly Bottom")
	)
	(footprint ""
		(layer "F.Cu")
		(at 68.212462 -40.437562)
		(property "Reference" "R3608"
			(at 0 0 0)
			(layer "F.SilkS")
			(hide yes)
			(effects
				(font
					(size 1.27 1.27)
				)
			)
		)
		(property "Value" ""
			(at 0 0 0)
			(layer "F.Fab")
			(effects
				(font
					(size 1.27 1.27)
				)
			)
		)
		(duplicate_pad_numbers_are_jumpers no)
		(fp_line
			(start -0.7874 -0.4064)
			(end 0.7874 -0.4064)
			(stroke
				(width 0.1524)
				(type default)
			)
			(layer "F.SilkS")
		)
		(fp_line
			(start -0.7874 0.4064)
			(end -0.7874 -0.4064)
			(stroke
				(width 0.1524)
				(type default)
			)
			(layer "F.SilkS")
		)
		(fp_line
			(start 0.7874 -0.4064)
			(end 0.7874 0.4064)
			(stroke
				(width 0.1524)
				(type default)
			)
			(layer "F.SilkS")
		)
		(fp_line
			(start 0.7874 0.4064)
			(end -0.7874 0.4064)
			(stroke
				(width 0.1524)
				(type default)
			)
			(layer "F.SilkS")
		)
		(fp_line
			(start -0.67945 -0.305054)
			(end -0.12065 -0.305054)
			(stroke
				(width 0.1)
				(type default)
			)
			(layer "F.Fab")
		)
		(fp_line
			(start -0.67945 0.3048)
			(end -0.67945 -0.305054)
			(stroke
				(width 0.1)
				(type default)
			)
			(layer "F.Fab")
		)
		(fp_line
			(start -0.12065 -0.305054)
			(end -0.12065 -0.2794)
			(stroke
				(width 0.1)
				(type default)
			)
			(layer "F.Fab")
		)
		(fp_line
			(start -0.12065 -0.2794)
			(end 0.12065 -0.2794)
			(stroke
				(width 0.1)
				(type default)
			)
			(layer "F.Fab")
		)
		(fp_line
			(start -0.12065 0.2794)
			(end -0.12065 0.3048)
			(stroke
				(width 0.1)
				(type default)
			)
			(layer "F.Fab")
		)
		(fp_line
			(start -0.12065 0.3048)
			(end -0.67945 0.3048)
			(stroke
				(width 0.1)
				(type default)
			)
			(layer "F.Fab")
		)
		(fp_line
			(start 0.120396 0.2794)
			(end -0.12065 0.2794)
			(stroke
				(width 0.1)
				(type default)
			)
			(layer "F.Fab")
		)
		(fp_line
			(start 0.120396 0.3048)
			(end 0.120396 0.2794)
			(stroke
				(width 0.1)
				(type default)
			)
			(layer "F.Fab")
		)
		(fp_line
			(start 0.12065 -0.3048)
			(end 0.67945 -0.3048)
			(stroke
				(width 0.1)
				(type default)
			)
			(layer "F.Fab")
		)
		(fp_line
			(start 0.12065 -0.2794)
			(end 0.12065 -0.3048)
			(stroke
				(width 0.1)
				(type default)
			)
			(layer "F.Fab")
		)
		(fp_line
			(start 0.67945 -0.3048)
			(end 0.67945 0.3048)
			(stroke
				(width 0.1)
				(type default)
			)
			(layer "F.Fab")
		)
		(fp_line
			(start 0.67945 0.3048)
			(end 0.120396 0.3048)
			(stroke
				(width 0.1)
				(type default)
			)
			(layer "F.Fab")
		)
		(pad "1" smd circle
			(at -0.40005 0)
			(size 0 0)
			(layers "F.Cu" "F.Mask" "F.Paste")
			(net "GND")
		)
		(pad "2" smd circle
			(at 0.40005 0)
			(size 0 0)
			(layers "F.Cu" "F.Mask" "F.Paste")
			(net "INA230_3_A1")
		)
	)
	(footprint ""
		(layer "F.Cu")
		(at 325.697342 -399.12798)
		(property "Reference" "R1364"
			(at 0 0 0)
			(layer "F.SilkS")
			(hide yes)
			(effects
				(font
					(size 1.27 1.27)
				)
			)
		)
		(property "Value" ""
			(at 0 0 0)
			(layer "F.Fab")
			(effects
				(font
					(size 1.27 1.27)
				)
			)
		)
		(duplicate_pad_numbers_are_jumpers no)
		(fp_line
			(start -0.32512 -0.175006)
			(end 0.32512 -0.175006)
			(stroke
				(width 0.1)
				(type default)
			)
			(layer "F.Fab")
		)
		(fp_line
			(start -0.32512 0.175006)
			(end -0.32512 -0.175006)
			(stroke
				(width 0.1)
				(type default)
			)
			(layer "F.Fab")
		)
		(fp_line
			(start 0.32512 -0.175006)
			(end 0.32512 0.175006)
			(stroke
				(width 0.1)
				(type default)
			)
			(layer "F.Fab")
		)
		(fp_line
			(start 0.32512 0.175006)
			(end -0.32512 0.175006)
			(stroke
				(width 0.1)
				(type default)
			)
			(layer "F.Fab")
		)
		(pad "1" smd rect
			(at -0.2667 0)
			(size 0.3048 0.381)
			(layers "F.Cu" "F.Mask" "F.Paste")
			(net "JTAG_TRST_RT_CPU0_P0_N")
		)
		(pad "2" smd rect
			(at 0.2667 0 180)
			(size 0.3048 0.381)
			(layers "F.Cu" "F.Mask" "F.Paste")
			(net "GND")
		)
	)
	(footprint ""
		(layer "F.Cu")
		(at 372.109492 -383.88163 -90)
		(property "Reference" "C892"
			(at 0 0 270)
			(layer "F.SilkS")
			(hide yes)
			(effects
				(font
					(size 1.27 1.27)
				)
			)
		)
		(property "Value" ""
			(at 0 0 270)
			(layer "F.Fab")
			(effects
				(font
					(size 1.27 1.27)
				)
			)
		)
		(duplicate_pad_numbers_are_jumpers no)
		(fp_line
			(start -0.299974 0.150114)
			(end -0.299974 -0.150114)
			(stroke
				(width 0.1)
				(type default)
			)
			(layer "F.Fab")
		)
		(fp_line
			(start 0.299974 0.150114)
			(end -0.299974 0.150114)
			(stroke
				(width 0.1)
				(type default)
			)
			(layer "F.Fab")
		)
		(fp_line
			(start -0.299974 -0.150114)
			(end 0.299974 -0.150114)
			(stroke
				(width 0.1)
				(type default)
			)
			(layer "F.Fab")
		)
		(fp_line
			(start 0.299974 -0.150114)
			(end 0.299974 0.150114)
			(stroke
				(width 0.1)
				(type default)
			)
			(layer "F.Fab")
		)
		(pad "1" smd rect
			(at -0.2667 0 270)
			(size 0.3048 0.381)
			(layers "F.Cu" "F.Mask" "F.Paste")
			(net "P5E_CPU0_P3_TX_C_DN<4>")
		)
		(pad "2" smd rect
			(at 0.2667 0 270)
			(size 0.3048 0.381)
			(layers "F.Cu" "F.Mask" "F.Paste")
			(net "P5E_CPU0_P3_TX_DN<4>")
		)
	)
	(footprint ""
		(layer "F.Cu")
		(at 355.08057 -402.7424 -90)
		(property "Reference" "R1041"
			(at 0 0 270)
			(layer "F.SilkS")
			(hide yes)
			(effects
				(font
					(size 1.27 1.27)
				)
			)
		)
		(property "Value" ""
			(at 0 0 270)
			(layer "F.Fab")
			(effects
				(font
					(size 1.27 1.27)
				)
			)
		)
		(duplicate_pad_numbers_are_jumpers no)
		(fp_line
			(start -0.32512 0.175006)
			(end -0.32512 -0.175006)
			(stroke
				(width 0.1)
				(type default)
			)
			(layer "F.Fab")
		)
		(fp_line
			(start 0.32512 0.175006)
			(end -0.32512 0.175006)
			(stroke
				(width 0.1)
				(type default)
			)
			(layer "F.Fab")
		)
		(fp_line
			(start -0.32512 -0.175006)
			(end 0.32512 -0.175006)
			(stroke
				(width 0.1)
				(type default)
			)
			(layer "F.Fab")
		)
		(fp_line
			(start 0.32512 -0.175006)
			(end 0.32512 0.175006)
			(stroke
				(width 0.1)
				(type default)
			)
			(layer "F.Fab")
		)
		(pad "1" smd rect
			(at -0.2667 0 270)
			(size 0.3048 0.381)
			(layers "F.Cu" "F.Mask" "F.Paste")
			(net "RT_CPU0_P1_VQPS")
		)
		(pad "2" smd rect
			(at 0.2667 0 90)
			(size 0.3048 0.381)
			(layers "F.Cu" "F.Mask" "F.Paste")
			(net "GND")
		)
	)
)
